# S9S_MB_2U (Grand Teton) — schematic netlist excerpt (pin names and nets, part order shuffled) for the footprints in the layout excerpt that follows; sources: Cadence DE-HDL packaged netlist, KiCad conversion of 03242023_DA0F0TMBIJ0_F0T_Motherboard_J_brd_V01_OCP.brd

R1293  Q_RES  22 1% CHIP  pkg 0402LF  page 154 : A = NCSI_BMC_RXD1_R ; B = RMII_OCP_BMC_RXD_1
R3516  Q_RES  0 5% CHIP  pkg 0402LF  page 227 : A = GPU_BASE_ID0 ; B = GPU_BASE_ID0_R

(kicad_pcb
	(version 20260206)
	(generator "pcbnew")
	(generator_version "10.0")
	(general
		(thickness 1.6)
		(legacy_teardrops no)
	)
	(paper "A4")
	(title_block
		(title "03242023_DA0F0TMBIJ0_F0T_Motherboard_J_brd_V01_OCP.brd")
		(comment 1 "Grand Teton / footprints 1400-1401 of 6105")
	)
	(layers
		(0 "F.Cu" signal "TOP")
		(4 "In1.Cu" signal "GND")
		(6 "In2.Cu" signal "IN1")
		(8 "In3.Cu" signal "GND1")
		(10 "In4.Cu" signal "IN2")
		(12 "In5.Cu" signal "GND2")
		(14 "In6.Cu" signal "IN3")
		(16 "In7.Cu" signal "GND3")
		(18 "In8.Cu" signal "VCC")
		(20 "In9.Cu" signal "VCC1")
		(22 "In10.Cu" signal "GND4")
		(24 "In11.Cu" signal "IN4")
		(26 "In12.Cu" signal "GND5")
		(28 "In13.Cu" signal "IN5")
		(30 "In14.Cu" signal "GND6")
		(32 "In15.Cu" signal "IN6")
		(34 "In16.Cu" signal "GND7")
		(2 "B.Cu" signal "BOTTOM")
		(9 "F.Adhes" user "F.Adhesive")
		(11 "B.Adhes" user "B.Adhesive")
		(13 "F.Paste" user "Package Geometry/Pastemask Top")
		(15 "B.Paste" user "Package Geometry/Pastemask Bottom")
		(5 "F.SilkS" user "Ref Des/Silkscreen Top")
		(7 "B.SilkS" user "Ref Des/Silkscreen Bottom")
		(1 "F.Mask" user "Board Geometry/Soldermask Top")
		(3 "B.Mask" user "Board Geometry/Soldermask Bottom")
		(17 "Dwgs.User" user "User.Drawings")
		(19 "Cmts.User" user "User.Comments")
		(21 "Eco1.User" user "User.Eco1")
		(23 "Eco2.User" user "User.Eco2")
		(25 "Edge.Cuts" user "Board Geometry/Outline")
		(27 "Margin" user)
		(31 "F.CrtYd" user "Package Geometry/Place Bound Top")
		(29 "B.CrtYd" user "Package Geometry/Place Bound Bottom")
		(35 "F.Fab" user "Ref Des/Assembly Top")
		(33 "B.Fab" user "Ref Des/Assembly Bottom")
	)
	(footprint ""
		(layer "F.Cu")
		(at 200.035414 -78.42377 180)
		(property "Reference" "R1293"
			(at 0 0 180)
			(layer "F.SilkS")
			(hide yes)
			(effects
				(font
					(size 1.27 1.27)
				)
			)
		)
		(property "Value" ""
			(at 0 0 180)
			(layer "F.Fab")
			(effects
				(font
					(size 1.27 1.27)
				)
			)
		)
		(duplicate_pad_numbers_are_jumpers no)
		(fp_line
			(start 0.7874 0.4064)
			(end -0.7874 0.4064)
			(stroke
				(width 0.1524)
				(type default)
			)
			(layer "F.SilkS")
		)
		(fp_line
			(start 0.7874 -0.4064)
			(end 0.7874 0.4064)
			(stroke
				(width 0.1524)
				(type default)
			)
			(layer "F.SilkS")
		)
		(fp_line
			(start -0.7874 0.4064)
			(end -0.7874 -0.4064)
			(stroke
				(width 0.1524)
				(type default)
			)
			(layer "F.SilkS")
		)
		(fp_line
			(start -0.7874 -0.4064)
			(end 0.7874 -0.4064)
			(stroke
				(width 0.1524)
				(type default)
			)
			(layer "F.SilkS")
		)
		(fp_line
			(start 0.67945 0.3048)
			(end 0.120396 0.3048)
			(stroke
				(width 0.1)
				(type default)
			)
			(layer "F.Fab")
		)
		(fp_line
			(start 0.67945 -0.3048)
			(end 0.67945 0.3048)
			(stroke
				(width 0.1)
				(type default)
			)
			(layer "F.Fab")
		)
		(fp_line
			(start 0.12065 -0.2794)
			(end 0.12065 -0.3048)
			(stroke
				(width 0.1)
				(type default)
			)
			(layer "F.Fab")
		)
		(fp_line
			(start 0.12065 -0.3048)
			(end 0.67945 -0.3048)
			(stroke
				(width 0.1)
				(type default)
			)
			(layer "F.Fab")
		)
		(fp_line
			(start 0.120396 0.3048)
			(end 0.120396 0.2794)
			(stroke
				(width 0.1)
				(type default)
			)
			(layer "F.Fab")
		)
		(fp_line
			(start 0.120396 0.2794)
			(end -0.12065 0.2794)
			(stroke
				(width 0.1)
				(type default)
			)
			(layer "F.Fab")
		)
		(fp_line
			(start -0.12065 0.3048)
			(end -0.67945 0.3048)
			(stroke
				(width 0.1)
				(type default)
			)
			(layer "F.Fab")
		)
		(fp_line
			(start -0.12065 0.2794)
			(end -0.12065 0.3048)
			(stroke
				(width 0.1)
				(type default)
			)
			(layer "F.Fab")
		)
		(fp_line
			(start -0.12065 -0.2794)
			(end 0.12065 -0.2794)
			(stroke
				(width 0.1)
				(type default)
			)
			(layer "F.Fab")
		)
		(fp_line
			(start -0.12065 -0.305054)
			(end -0.12065 -0.2794)
			(stroke
				(width 0.1)
				(type default)
			)
			(layer "F.Fab")
		)
		(fp_line
			(start -0.67945 0.3048)
			(end -0.67945 -0.305054)
			(stroke
				(width 0.1)
				(type default)
			)
			(layer "F.Fab")
		)
		(fp_line
			(start -0.67945 -0.305054)
			(end -0.12065 -0.305054)
			(stroke
				(width 0.1)
				(type default)
			)
			(layer "F.Fab")
		)
		(pad "1" smd circle
			(at -0.40005 0 180)
			(size 0 0)
			(layers "F.Cu" "F.Mask" "F.Paste")
			(net "NCSI_BMC_RXD1_R")
		)
		(pad "2" smd circle
			(at 0.40005 0 180)
			(size 0 0)
			(layers "F.Cu" "F.Mask" "F.Paste")
			(net "RMII_OCP_BMC_RXD_1")
		)
	)
	(footprint ""
		(layer "F.Cu")
		(at 20.785582 -423.629836 -90)
		(property "Reference" "R3516"
			(at 0 0 270)
			(layer "F.SilkS")
			(hide yes)
			(effects
				(font
					(size 1.27 1.27)
				)
			)
		)
		(property "Value" ""
			(at 0 0 270)
			(layer "F.Fab")
			(effects
				(font
					(size 1.27 1.27)
				)
			)
		)
		(duplicate_pad_numbers_are_jumpers no)
		(fp_line
			(start -0.7874 0.4064)
			(end -0.7874 -0.4064)
			(stroke
				(width 0.1524)
				(type default)
			)
			(layer "F.SilkS")
		)
		(fp_line
			(start 0.7874 0.4064)
			(end -0.7874 0.4064)
			(stroke
				(width 0.1524)
				(type default)
			)
			(layer "F.SilkS")
		)
		(fp_line
			(start -0.7874 -0.4064)
			(end 0.7874 -0.4064)
			(stroke
				(width 0.1524)
				(type default)
			)
			(layer "F.SilkS")
		)
		(fp_line
			(start 0.7874 -0.4064)
			(end 0.7874 0.4064)
			(stroke
				(width 0.1524)
				(type default)
			)
			(layer "F.SilkS")
		)
		(fp_line
			(start -0.67945 0.3048)
			(end -0.67945 -0.305054)
			(stroke
				(width 0.1)
				(type default)
			)
			(layer "F.Fab")
		)
		(fp_line
			(start -0.12065 0.3048)
			(end -0.67945 0.3048)
			(stroke
				(width 0.1)
				(type default)
			)
			(layer "F.Fab")
		)
		(fp_line
			(start 0.120396 0.3048)
			(end 0.120396 0.2794)
			(stroke
				(width 0.1)
				(type default)
			)
			(layer "F.Fab")
		)
		(fp_line
			(start 0.67945 0.3048)
			(end 0.120396 0.3048)
			(stroke
				(width 0.1)
				(type default)
			)
			(layer "F.Fab")
		)
		(fp_line
			(start -0.12065 0.2794)
			(end -0.12065 0.3048)
			(stroke
				(width 0.1)
				(type default)
			)
			(layer "F.Fab")
		)
		(fp_line
			(start 0.120396 0.2794)
			(end -0.12065 0.2794)
			(stroke
				(width 0.1)
				(type default)
			)
			(layer "F.Fab")
		)
		(fp_line
			(start -0.12065 -0.2794)
			(end 0.12065 -0.2794)
			(stroke
				(width 0.1)
				(type default)
			)
			(layer "F.Fab")
		)
		(fp_line
			(start 0.12065 -0.2794)
			(end 0.12065 -0.3048)
			(stroke
				(width 0.1)
				(type default)
			)
			(layer "F.Fab")
		)
		(fp_line
			(start 0.12065 -0.3048)
			(end 0.67945 -0.3048)
			(stroke
				(width 0.1)
				(type default)
			)
			(layer "F.Fab")
		)
		(fp_line
			(start 0.67945 -0.3048)
			(end 0.67945 0.3048)
			(stroke
				(width 0.1)
				(type default)
			)
			(layer "F.Fab")
		)
		(fp_line
			(start -0.67945 -0.305054)
			(end -0.12065 -0.305054)
			(stroke
				(width 0.1)
				(type default)
			)
			(layer "F.Fab")
		)
		(fp_line
			(start -0.12065 -0.305054)
			(end -0.12065 -0.2794)
			(stroke
				(width 0.1)
				(type default)
			)
			(layer "F.Fab")
		)
		(pad "1" smd circle
			(at -0.40005 0 270)
			(size 0 0)
			(layers "F.Cu" "F.Mask" "F.Paste")
			(net "GPU_BASE_ID0")
		)
		(pad "2" smd circle
			(at 0.40005 0 270)
			(size 0 0)
			(layers "F.Cu" "F.Mask" "F.Paste")
			(net "GPU_BASE_ID0_R")
		)
	)
)
